# T6G (Grand Teton) — schematic netlist excerpt (pin names and nets, part order shuffled) for the footprints in the layout excerpt that follows; sources: Cadence DE-HDL packaged netlist, KiCad conversion of 04192023_DAF0TMB3IC0_F0TG_MB_C_brd_V02_OCP.brd

R894  Q_RES  0 5% EMPTY  pkg 0402LF  page 356 : A = P1V8_CPU1_RT3_1A_1D ; B = P1V8_CPU1_RT3_1A
PC6502  Q_CAP  22UF 16V 20% X6S  pkg C0805  page 360 : A = SW_P12V_AUX_P1V8_RETIMER_CPU0_FLT ; B = GND

U37  74LVC1G32GW  IC  pkg SMLF  page 142
  I0  = HP_LVC3_OCP_V3_2_PWRGD_R1
  I1  = FM_OCP_V3_2_AUX_PWR_R_EN
  GND  = GND
  O  = OCP_V3_2_AUX_PWR_EN_R2
  VCC  = P3V3_AUX

(kicad_pcb
	(version 20260206)
	(generator "pcbnew")
	(generator_version "10.0")
	(general
		(thickness 1.6)
		(legacy_teardrops no)
	)
	(paper "A4")
	(title_block
		(title "04192023_DAF0TMB3IC0_F0TG_MB_C_brd_V02_OCP.brd")
		(comment 1 "Grand Teton / footprints 4104-4106 of 8354")
	)
	(layers
		(0 "F.Cu" signal "TOP")
		(4 "In1.Cu" signal "GND")
		(6 "In2.Cu" signal "IN1")
		(8 "In3.Cu" signal "GND1")
		(10 "In4.Cu" signal "IN2")
		(12 "In5.Cu" signal "GND2")
		(14 "In6.Cu" signal "IN3")
		(16 "In7.Cu" signal "GND3")
		(18 "In8.Cu" signal "VCC")
		(20 "In9.Cu" signal "VCC1")
		(22 "In10.Cu" signal "GND4")
		(24 "In11.Cu" signal "IN4")
		(26 "In12.Cu" signal "GND5")
		(28 "In13.Cu" signal "IN5")
		(30 "In14.Cu" signal "GND6")
		(32 "In15.Cu" signal "IN6")
		(34 "In16.Cu" signal "GND7")
		(2 "B.Cu" signal "BOTTOM")
		(9 "F.Adhes" user "F.Adhesive")
		(11 "B.Adhes" user "B.Adhesive")
		(13 "F.Paste" user "Package Geometry/Pastemask Top")
		(15 "B.Paste" user "Package Geometry/Pastemask Bottom")
		(5 "F.SilkS" user "Ref Des/Silkscreen Top")
		(7 "B.SilkS" user "Ref Des/Silkscreen Bottom")
		(1 "F.Mask" user "Board Geometry/Soldermask Top")
		(3 "B.Mask" user "Board Geometry/Soldermask Bottom")
		(17 "Dwgs.User" user "User.Drawings")
		(19 "Cmts.User" user "User.Comments")
		(21 "Eco1.User" user "User.Eco1")
		(23 "Eco2.User" user "User.Eco2")
		(25 "Edge.Cuts" user "Board Geometry/Outline")
		(27 "Margin" user)
		(31 "F.CrtYd" user "Package Geometry/Place Bound Top")
		(29 "B.CrtYd" user "Package Geometry/Place Bound Bottom")
		(35 "F.Fab" user "Ref Des/Assembly Top")
		(33 "B.Fab" user "Ref Des/Assembly Bottom")
	)
	(footprint ""
		(layer "F.Cu")
		(at 136.962388 -385.09448 180)
		(property "Reference" "R894"
			(at 0 0 180)
			(layer "F.SilkS")
			(hide yes)
			(effects
				(font
					(size 1.27 1.27)
				)
			)
		)
		(property "Value" ""
			(at 0 0 180)
			(layer "F.Fab")
			(effects
				(font
					(size 1.27 1.27)
				)
			)
		)
		(duplicate_pad_numbers_are_jumpers no)
		(fp_line
			(start 0.7874 0.4064)
			(end -0.7874 0.4064)
			(stroke
				(width 0.1524)
				(type default)
			)
			(layer "F.SilkS")
		)
		(fp_line
			(start 0.7874 -0.4064)
			(end 0.7874 0.4064)
			(stroke
				(width 0.1524)
				(type default)
			)
			(layer "F.SilkS")
		)
		(fp_line
			(start -0.7874 0.4064)
			(end -0.7874 -0.4064)
			(stroke
				(width 0.1524)
				(type default)
			)
			(layer "F.SilkS")
		)
		(fp_line
			(start -0.7874 -0.4064)
			(end 0.7874 -0.4064)
			(stroke
				(width 0.1524)
				(type default)
			)
			(layer "F.SilkS")
		)
		(fp_line
			(start 0.67945 0.3048)
			(end 0.120396 0.3048)
			(stroke
				(width 0.1)
				(type default)
			)
			(layer "F.Fab")
		)
		(fp_line
			(start 0.67945 -0.3048)
			(end 0.67945 0.3048)
			(stroke
				(width 0.1)
				(type default)
			)
			(layer "F.Fab")
		)
		(fp_line
			(start 0.12065 -0.2794)
			(end 0.12065 -0.3048)
			(stroke
				(width 0.1)
				(type default)
			)
			(layer "F.Fab")
		)
		(fp_line
			(start 0.12065 -0.3048)
			(end 0.67945 -0.3048)
			(stroke
				(width 0.1)
				(type default)
			)
			(layer "F.Fab")
		)
		(fp_line
			(start 0.120396 0.3048)
			(end 0.120396 0.2794)
			(stroke
				(width 0.1)
				(type default)
			)
			(layer "F.Fab")
		)
		(fp_line
			(start 0.120396 0.2794)
			(end -0.12065 0.2794)
			(stroke
				(width 0.1)
				(type default)
			)
			(layer "F.Fab")
		)
		(fp_line
			(start -0.12065 0.3048)
			(end -0.67945 0.3048)
			(stroke
				(width 0.1)
				(type default)
			)
			(layer "F.Fab")
		)
		(fp_line
			(start -0.12065 0.2794)
			(end -0.12065 0.3048)
			(stroke
				(width 0.1)
				(type default)
			)
			(layer "F.Fab")
		)
		(fp_line
			(start -0.12065 -0.2794)
			(end 0.12065 -0.2794)
			(stroke
				(width 0.1)
				(type default)
			)
			(layer "F.Fab")
		)
		(fp_line
			(start -0.12065 -0.305054)
			(end -0.12065 -0.2794)
			(stroke
				(width 0.1)
				(type default)
			)
			(layer "F.Fab")
		)
		(fp_line
			(start -0.67945 0.3048)
			(end -0.67945 -0.305054)
			(stroke
				(width 0.1)
				(type default)
			)
			(layer "F.Fab")
		)
		(fp_line
			(start -0.67945 -0.305054)
			(end -0.12065 -0.305054)
			(stroke
				(width 0.1)
				(type default)
			)
			(layer "F.Fab")
		)
		(pad "1" smd rect
			(at -0.40005 0)
			(size 0.4572 0.508)
			(layers "F.Cu" "F.Mask" "F.Paste")
			(net "P1V8_CPU1_RT3_1A_1D")
		)
		(pad "2" smd rect
			(at 0.40005 0)
			(size 0.4572 0.508)
			(layers "F.Cu" "F.Mask" "F.Paste")
			(net "P1V8_CPU1_RT3_1A")
		)
	)
	(footprint ""
		(layer "F.Cu")
		(at 69.85 -56.642)
		(property "Reference" "U37"
			(at -3.023108 -2.564384 0)
			(unlocked yes)
			(layer "F.SilkS")
			(effects
				(font
					(size 0.7874 0.5842)
					(thickness 0.1524)
				)
				(justify left)
			)
		)
		(property "Value" ""
			(at 0 0 0)
			(layer "F.Fab")
			(effects
				(font
					(size 1.27 1.27)
				)
			)
		)
		(duplicate_pad_numbers_are_jumpers no)
		(fp_line
			(start -1.4986 -1.100074)
			(end 1.4986 -1.100074)
			(stroke
				(width 0.1524)
				(type default)
			)
			(layer "F.SilkS")
		)
		(fp_line
			(start -1.4986 1.100074)
			(end -1.4986 -1.100074)
			(stroke
				(width 0.1524)
				(type default)
			)
			(layer "F.SilkS")
		)
		(fp_line
			(start 1.4986 -1.100074)
			(end 1.4986 1.100074)
			(stroke
				(width 0.1524)
				(type default)
			)
			(layer "F.SilkS")
		)
		(fp_line
			(start 1.4986 1.100074)
			(end -1.4986 1.100074)
			(stroke
				(width 0.1524)
				(type default)
			)
			(layer "F.SilkS")
		)
		(fp_poly
			(pts
				(xy -2.20472 -0.338328) (xy -2.20472 -0.963168) (xy -1.651 -0.635)
			)
			(stroke
				(width 0)
				(type default)
			)
			(fill yes)
			(layer "F.SilkS")
		)
		(fp_line
			(start -0.67437 -1.100074)
			(end 0.67437 -1.100074)
			(stroke
				(width 0.1)
				(type default)
			)
			(layer "F.Fab")
		)
		(fp_line
			(start -0.67437 1.100074)
			(end -0.67437 -1.100074)
			(stroke
				(width 0.1)
				(type default)
			)
			(layer "F.Fab")
		)
		(fp_line
			(start 0.67437 -1.100074)
			(end 0.67437 1.100074)
			(stroke
				(width 0.1)
				(type default)
			)
			(layer "F.Fab")
		)
		(fp_line
			(start 0.67437 1.100074)
			(end -0.67437 1.100074)
			(stroke
				(width 0.1)
				(type default)
			)
			(layer "F.Fab")
		)
		(fp_poly
			(pts
				(xy -2.20472 -0.338328) (xy -2.20472 -0.963168) (xy -1.651 -0.635)
			)
			(stroke
				(width 0)
				(type default)
			)
			(fill yes)
			(layer "F.Fab")
		)
		(pad "1" smd rect
			(at -0.889 -0.649986)
			(size 1.016 0.381)
			(layers "F.Cu" "F.Mask" "F.Paste")
			(net "HP_LVC3_OCP_V3_2_PWRGD_R1")
		)
		(pad "2" smd rect
			(at -0.889 0)
			(size 1.016 0.381)
			(layers "F.Cu" "F.Mask" "F.Paste")
			(net "FM_OCP_V3_2_AUX_PWR_R_EN")
		)
		(pad "3" smd rect
			(at -0.889 0.649986)
			(size 1.016 0.381)
			(layers "F.Cu" "F.Mask" "F.Paste")
			(net "GND")
		)
		(pad "4" smd rect
			(at 0.889 0.649986)
			(size 1.016 0.381)
			(layers "F.Cu" "F.Mask" "F.Paste")
			(net "OCP_V3_2_AUX_PWR_EN_R2")
		)
		(pad "5" smd rect
			(at 0.889 -0.649986)
			(size 1.016 0.381)
			(layers "F.Cu" "F.Mask" "F.Paste")
			(net "P3V3_AUX")
		)
	)
	(footprint ""
		(layer "F.Cu")
		(at 244.327426 -283.853636)
		(property "Reference" "PC6502"
			(at 0 0 0)
			(layer "F.SilkS")
			(hide yes)
			(effects
				(font
					(size 1.27 1.27)
				)
			)
		)
		(property "Value" ""
			(at 0 0 0)
			(layer "F.Fab")
			(effects
				(font
					(size 1.27 1.27)
				)
			)
		)
		(duplicate_pad_numbers_are_jumpers no)
		(fp_line
			(start -1.524 -0.762)
			(end 1.524 -0.762)
			(stroke
				(width 0.1524)
				(type default)
			)
			(layer "F.SilkS")
		)
		(fp_line
			(start -1.524 0.762)
			(end -1.524 -0.762)
			(stroke
				(width 0.1524)
				(type default)
			)
			(layer "F.SilkS")
		)
		(fp_line
			(start 1.524 -0.762)
			(end 1.524 0.762)
			(stroke
				(width 0.1524)
				(type default)
			)
			(layer "F.SilkS")
		)
		(fp_line
			(start 1.524 0.762)
			(end -1.524 0.762)
			(stroke
				(width 0.1524)
				(type default)
			)
			(layer "F.SilkS")
		)
		(fp_line
			(start -1.1049 -0.724916)
			(end -1.1049 0.724916)
			(stroke
				(width 0.1)
				(type default)
			)
			(layer "F.Fab")
		)
		(fp_line
			(start -1.1049 0.724916)
			(end 1.1049 0.724916)
			(stroke
				(width 0.1)
				(type default)
			)
			(layer "F.Fab")
		)
		(fp_line
			(start 1.1049 -0.724916)
			(end -1.1049 -0.724916)
			(stroke
				(width 0.1)
				(type default)
			)
			(layer "F.Fab")
		)
		(fp_line
			(start 1.1049 0.724916)
			(end 1.1049 -0.724916)
			(stroke
				(width 0.1)
				(type default)
			)
			(layer "F.Fab")
		)
		(pad "1" smd rect
			(at -0.889 0 180)
			(size 1.016 1.27)
			(layers "F.Cu" "F.Mask" "F.Paste")
			(net "SW_P12V_AUX_P1V8_RETIMER_CPU0_FLT")
		)
		(pad "2" smd rect
			(at 0.889 0 180)
			(size 1.016 1.27)
			(layers "F.Cu" "F.Mask" "F.Paste")
			(net "GND")
		)
	)
)
